# BASEBOARD_FAB2 (Tioga Pass) — schematic netlist excerpt (pin names and nets, part order shuffled) for the footprints in the layout excerpt that follows; sources: Cadence DE-HDL packaged netlist, KiCad conversion of Wiwynn_Tioga_Pass_MB.brd

R2T22  RES  10.0K 1% CHIP  pkg 0402  page 156 : A = P3V3_STBY ; B = RST_BMC_SYSRST_BTN_OUT_B_R_N
R7L2  RES  100.0 1% EMPTY  pkg 0402  page 228 : A = VSENSE_PVDDQ_KLM_P ; B = VSENSE_PVDDQ_KLM_N
R8N3  RES  10.0K 1% CHIP  pkg 0402  page 55 : A = P3V3_STBY ; B = FM_CPU1_PKGID2

(kicad_pcb
	(version 20260206)
	(generator "pcbnew")
	(generator_version "10.0")
	(general
		(thickness 1.6)
		(legacy_teardrops no)
	)
	(paper "A4")
	(title_block
		(title "Wiwynn_Tioga_Pass_MB.brd")
		(comment 1 "Tioga Pass / footprints 4524-4526 of 4770")
	)
	(layers
		(0 "F.Cu" signal "TOP")
		(4 "In1.Cu" signal "L2GND")
		(6 "In2.Cu" signal "L3")
		(8 "In3.Cu" signal "L4GND")
		(10 "In4.Cu" signal "L5")
		(12 "In5.Cu" signal "L6GND")
		(14 "In6.Cu" signal "L7VCC")
		(16 "In7.Cu" signal "L8VCC")
		(18 "In8.Cu" signal "L9GND")
		(20 "In9.Cu" signal "L10")
		(22 "In10.Cu" signal "L11GND")
		(24 "In11.Cu" signal "L12")
		(26 "In12.Cu" signal "L13GND")
		(2 "B.Cu" signal "BOTTOM")
		(9 "F.Adhes" user "F.Adhesive")
		(11 "B.Adhes" user "B.Adhesive")
		(13 "F.Paste" user "Package Geometry/Pastemask Top")
		(15 "B.Paste" user "Package Geometry/Pastemask Bottom")
		(5 "F.SilkS" user "Ref Des/Silkscreen Top")
		(7 "B.SilkS" user "Ref Des/Silkscreen Bottom")
		(1 "F.Mask" user "Board Geometry/Soldermask Top")
		(3 "B.Mask" user "Board Geometry/Soldermask Bottom")
		(17 "Dwgs.User" user "User.Drawings")
		(19 "Cmts.User" user "User.Comments")
		(21 "Eco1.User" user "User.Eco1")
		(23 "Eco2.User" user "User.Eco2")
		(25 "Edge.Cuts" user "Board Geometry/Outline")
		(27 "Margin" user)
		(31 "F.CrtYd" user "Package Geometry/Place Bound Top")
		(29 "B.CrtYd" user "Package Geometry/Place Bound Bottom")
		(35 "F.Fab" user "Ref Des/Assembly Top")
		(33 "B.Fab" user "Ref Des/Assembly Bottom")
	)
	(footprint ""
		(layer "B.Cu")
		(at 63.2968 -91.1352 90)
		(property "Reference" "R8N3"
			(at 0 0 90)
			(layer "B.SilkS")
			(hide yes)
			(effects
				(font
					(size 1.27 1.27)
				)
				(justify mirror)
			)
		)
		(property "Value" ""
			(at 0 0 90)
			(layer "B.Fab")
			(effects
				(font
					(size 1.27 1.27)
				)
				(justify mirror)
			)
		)
		(duplicate_pad_numbers_are_jumpers no)
		(fp_poly
			(pts
				(xy 0.2794 -0.1016) (xy -0.2794 -0.1016) (xy -0.2794 0.9906) (xy 0.2794 0.9906)
			)
			(stroke
				(width 0)
				(type default)
			)
			(fill no)
			(layer "B.CrtYd")
		)
		(fp_line
			(start 0.2794 -0.1016)
			(end 0.2794 0.9906)
			(stroke
				(width 0.1)
				(type default)
			)
			(layer "B.Fab")
		)
		(fp_line
			(start -0.2794 -0.1016)
			(end 0.2794 -0.1016)
			(stroke
				(width 0.1)
				(type default)
			)
			(layer "B.Fab")
		)
		(fp_line
			(start 0.2794 0.9906)
			(end -0.2794 0.9906)
			(stroke
				(width 0.1)
				(type default)
			)
			(layer "B.Fab")
		)
		(fp_line
			(start -0.2794 0.9906)
			(end -0.2794 -0.1016)
			(stroke
				(width 0.1)
				(type default)
			)
			(layer "B.Fab")
		)
		(pad "1" smd rect
			(at 0 0 270)
			(size 0.508 0.508)
			(layers "B.Cu" "B.Mask" "B.Paste")
			(net "P3V3_STBY")
		)
		(pad "2" smd rect
			(at 0 0.889 270)
			(size 0.508 0.508)
			(layers "B.Cu" "B.Mask" "B.Paste")
			(net "FM_CPU1_PKGID2")
		)
		(zone
			(layer "B.Cu")
			(hatch none 0.5)
			(connect_pads
				(clearance 0)
			)
			(min_thickness 0.25)
			(keepout
				(tracks allowed)
				(vias not_allowed)
				(pads allowed)
				(copperpour not_allowed)
				(footprints allowed)
			)
			(placement
				(enabled no)
				(sheetname "")
			)
			(fill
				(thermal_gap 0.5)
				(thermal_bridge_width 0.5)
				(island_removal_mode 0)
			)
			(polygon
				(pts
					(xy 63.5508 -91.3892) (xy 63.5508 -90.8812) (xy 63.9318 -90.8812) (xy 63.9318 -91.3892)
				)
			)
		)
		(zone
			(layer "B.Cu")
			(hatch none 0.5)
			(connect_pads
				(clearance 0)
			)
			(min_thickness 0.25)
			(keepout
				(tracks not_allowed)
				(vias allowed)
				(pads allowed)
				(copperpour not_allowed)
				(footprints allowed)
			)
			(placement
				(enabled no)
				(sheetname "")
			)
			(fill
				(thermal_gap 0.5)
				(thermal_bridge_width 0.5)
				(island_removal_mode 0)
			)
			(polygon
				(pts
					(xy 63.9318 -91.3892) (xy 63.9318 -90.8812) (xy 63.5508 -90.8812) (xy 63.5508 -91.3892)
				)
			)
		)
	)
	(footprint ""
		(layer "B.Cu")
		(at 86.436708 -125.99162 90)
		(property "Reference" "R7L2"
			(at 0 0 90)
			(layer "B.SilkS")
			(hide yes)
			(effects
				(font
					(size 1.27 1.27)
				)
				(justify mirror)
			)
		)
		(property "Value" ""
			(at 0 0 90)
			(layer "B.Fab")
			(effects
				(font
					(size 1.27 1.27)
				)
				(justify mirror)
			)
		)
		(duplicate_pad_numbers_are_jumpers no)
		(fp_poly
			(pts
				(xy 0.2794 -0.1016) (xy -0.2794 -0.1016) (xy -0.2794 0.9906) (xy 0.2794 0.9906)
			)
			(stroke
				(width 0)
				(type default)
			)
			(fill no)
			(layer "B.CrtYd")
		)
		(fp_line
			(start 0.2794 -0.1016)
			(end 0.2794 0.9906)
			(stroke
				(width 0.1)
				(type default)
			)
			(layer "B.Fab")
		)
		(fp_line
			(start -0.2794 -0.1016)
			(end 0.2794 -0.1016)
			(stroke
				(width 0.1)
				(type default)
			)
			(layer "B.Fab")
		)
		(fp_line
			(start 0.2794 0.9906)
			(end -0.2794 0.9906)
			(stroke
				(width 0.1)
				(type default)
			)
			(layer "B.Fab")
		)
		(fp_line
			(start -0.2794 0.9906)
			(end -0.2794 -0.1016)
			(stroke
				(width 0.1)
				(type default)
			)
			(layer "B.Fab")
		)
		(pad "1" smd rect
			(at 0 0 270)
			(size 0.508 0.508)
			(layers "B.Cu" "B.Mask" "B.Paste")
			(net "VSENSE_PVDDQ_KLM_P")
		)
		(pad "2" smd rect
			(at 0 0.889 270)
			(size 0.508 0.508)
			(layers "B.Cu" "B.Mask" "B.Paste")
			(net "VSENSE_PVDDQ_KLM_N")
		)
		(zone
			(layer "B.Cu")
			(hatch none 0.5)
			(connect_pads
				(clearance 0)
			)
			(min_thickness 0.25)
			(keepout
				(tracks allowed)
				(vias not_allowed)
				(pads allowed)
				(copperpour not_allowed)
				(footprints allowed)
			)
			(placement
				(enabled no)
				(sheetname "")
			)
			(fill
				(thermal_gap 0.5)
				(thermal_bridge_width 0.5)
				(island_removal_mode 0)
			)
			(polygon
				(pts
					(xy 86.690708 -126.24562) (xy 86.690708 -125.73762) (xy 87.071708 -125.73762) (xy 87.071708 -126.24562)
				)
			)
		)
		(zone
			(layer "B.Cu")
			(hatch none 0.5)
			(connect_pads
				(clearance 0)
			)
			(min_thickness 0.25)
			(keepout
				(tracks not_allowed)
				(vias allowed)
				(pads allowed)
				(copperpour not_allowed)
				(footprints allowed)
			)
			(placement
				(enabled no)
				(sheetname "")
			)
			(fill
				(thermal_gap 0.5)
				(thermal_bridge_width 0.5)
				(island_removal_mode 0)
			)
			(polygon
				(pts
					(xy 87.071708 -126.24562) (xy 87.071708 -125.73762) (xy 86.690708 -125.73762) (xy 86.690708 -126.24562)
				)
			)
		)
	)
	(footprint ""
		(layer "B.Cu")
		(at 395.478 -29.845 -90)
		(property "Reference" "R2T22"
			(at 0 0 90)
			(layer "B.SilkS")
			(hide yes)
			(effects
				(font
					(size 1.27 1.27)
				)
				(justify mirror)
			)
		)
		(property "Value" ""
			(at 0 0 90)
			(layer "B.Fab")
			(effects
				(font
					(size 1.27 1.27)
				)
				(justify mirror)
			)
		)
		(duplicate_pad_numbers_are_jumpers no)
		(fp_poly
			(pts
				(xy 0.2794 -0.1016) (xy -0.2794 -0.1016) (xy -0.2794 0.9906) (xy 0.2794 0.9906)
			)
			(stroke
				(width 0)
				(type default)
			)
			(fill no)
			(layer "B.CrtYd")
		)
		(fp_line
			(start -0.2794 0.9906)
			(end -0.2794 -0.1016)
			(stroke
				(width 0.1)
				(type default)
			)
			(layer "B.Fab")
		)
		(fp_line
			(start 0.2794 0.9906)
			(end -0.2794 0.9906)
			(stroke
				(width 0.1)
				(type default)
			)
			(layer "B.Fab")
		)
		(fp_line
			(start -0.2794 -0.1016)
			(end 0.2794 -0.1016)
			(stroke
				(width 0.1)
				(type default)
			)
			(layer "B.Fab")
		)
		(fp_line
			(start 0.2794 -0.1016)
			(end 0.2794 0.9906)
			(stroke
				(width 0.1)
				(type default)
			)
			(layer "B.Fab")
		)
		(pad "1" smd rect
			(at 0 0 90)
			(size 0.508 0.508)
			(layers "B.Cu" "B.Mask" "B.Paste")
			(net "P3V3_STBY")
		)
		(pad "2" smd rect
			(at 0 0.889 90)
			(size 0.508 0.508)
			(layers "B.Cu" "B.Mask" "B.Paste")
			(net "RST_BMC_SYSRST_BTN_OUT_B_R_N")
		)
	)
)
